# BASEBOARD_FAB2 (Tioga Pass) — schematic netlist excerpt (pin names and nets, part order shuffled) for the footprints in the layout excerpt that follows; sources: Cadence DE-HDL packaged netlist, KiCad conversion of Wiwynn_Tioga_Pass_MB.brd

R3P20  RES  22.1 1.0% CHIP  pkg 0402  page 211 : A = PWRGD_PVCCIO_CPU0_R ; B = PWRGD_PVCCIO_CPU0
SH7L1  SHUNT  EMPTY  pkg SH0201  page 228 : A = VSENSE_PVDDQ_KLM_N ; B = GND
C2R1  CAP_A  0.1UF 16V 10% X7R  pkg 0402V  page 192 : A = P3V3_STBY ; B = GND

(kicad_pcb
	(version 20260206)
	(generator "pcbnew")
	(generator_version "10.0")
	(general
		(thickness 1.6)
		(legacy_teardrops no)
	)
	(paper "A4")
	(title_block
		(title "Wiwynn_Tioga_Pass_MB.brd")
		(comment 1 "Tioga Pass / footprints 3080-3082 of 4770")
	)
	(layers
		(0 "F.Cu" signal "TOP")
		(4 "In1.Cu" signal "L2GND")
		(6 "In2.Cu" signal "L3")
		(8 "In3.Cu" signal "L4GND")
		(10 "In4.Cu" signal "L5")
		(12 "In5.Cu" signal "L6GND")
		(14 "In6.Cu" signal "L7VCC")
		(16 "In7.Cu" signal "L8VCC")
		(18 "In8.Cu" signal "L9GND")
		(20 "In9.Cu" signal "L10")
		(22 "In10.Cu" signal "L11GND")
		(24 "In11.Cu" signal "L12")
		(26 "In12.Cu" signal "L13GND")
		(2 "B.Cu" signal "BOTTOM")
		(9 "F.Adhes" user "F.Adhesive")
		(11 "B.Adhes" user "B.Adhesive")
		(13 "F.Paste" user "Package Geometry/Pastemask Top")
		(15 "B.Paste" user "Package Geometry/Pastemask Bottom")
		(5 "F.SilkS" user "Ref Des/Silkscreen Top")
		(7 "B.SilkS" user "Ref Des/Silkscreen Bottom")
		(1 "F.Mask" user "Board Geometry/Soldermask Top")
		(3 "B.Mask" user "Board Geometry/Soldermask Bottom")
		(17 "Dwgs.User" user "User.Drawings")
		(19 "Cmts.User" user "User.Comments")
		(21 "Eco1.User" user "User.Eco1")
		(23 "Eco2.User" user "User.Eco2")
		(25 "Edge.Cuts" user "Board Geometry/Outline")
		(27 "Margin" user)
		(31 "F.CrtYd" user "Package Geometry/Place Bound Top")
		(29 "B.CrtYd" user "Package Geometry/Place Bound Bottom")
		(35 "F.Fab" user "Ref Des/Assembly Top")
		(33 "B.Fab" user "Ref Des/Assembly Bottom")
	)
	(footprint ""
		(layer "B.Cu")
		(at 343.789 -83.566)
		(property "Reference" "R3P20"
			(at 0 0 0)
			(layer "B.SilkS")
			(hide yes)
			(effects
				(font
					(size 1.27 1.27)
				)
				(justify mirror)
			)
		)
		(property "Value" ""
			(at 0 0 0)
			(layer "B.Fab")
			(effects
				(font
					(size 1.27 1.27)
				)
				(justify mirror)
			)
		)
		(duplicate_pad_numbers_are_jumpers no)
		(fp_poly
			(pts
				(xy 0.2794 -0.1016) (xy -0.2794 -0.1016) (xy -0.2794 0.9906) (xy 0.2794 0.9906)
			)
			(stroke
				(width 0)
				(type default)
			)
			(fill no)
			(layer "B.CrtYd")
		)
		(fp_line
			(start -0.2794 -0.1016)
			(end 0.2794 -0.1016)
			(stroke
				(width 0.1)
				(type default)
			)
			(layer "B.Fab")
		)
		(fp_line
			(start -0.2794 0.9906)
			(end -0.2794 -0.1016)
			(stroke
				(width 0.1)
				(type default)
			)
			(layer "B.Fab")
		)
		(fp_line
			(start 0.2794 -0.1016)
			(end 0.2794 0.9906)
			(stroke
				(width 0.1)
				(type default)
			)
			(layer "B.Fab")
		)
		(fp_line
			(start 0.2794 0.9906)
			(end -0.2794 0.9906)
			(stroke
				(width 0.1)
				(type default)
			)
			(layer "B.Fab")
		)
		(pad "1" smd rect
			(at 0 0 180)
			(size 0.508 0.508)
			(layers "B.Cu" "B.Mask" "B.Paste")
			(net "PWRGD_PVCCIO_CPU0_R")
		)
		(pad "2" smd rect
			(at 0 0.889 180)
			(size 0.508 0.508)
			(layers "B.Cu" "B.Mask" "B.Paste")
			(net "PWRGD_PVCCIO_CPU0")
		)
		(zone
			(layer "B.Cu")
			(hatch none 0.5)
			(connect_pads
				(clearance 0)
			)
			(min_thickness 0.25)
			(keepout
				(tracks allowed)
				(vias not_allowed)
				(pads allowed)
				(copperpour not_allowed)
				(footprints allowed)
			)
			(placement
				(enabled no)
				(sheetname "")
			)
			(fill
				(thermal_gap 0.5)
				(thermal_bridge_width 0.5)
				(island_removal_mode 0)
			)
			(polygon
				(pts
					(xy 344.043 -83.312) (xy 343.535 -83.312) (xy 343.535 -82.931) (xy 344.043 -82.931)
				)
			)
		)
		(zone
			(layer "B.Cu")
			(hatch none 0.5)
			(connect_pads
				(clearance 0)
			)
			(min_thickness 0.25)
			(keepout
				(tracks not_allowed)
				(vias allowed)
				(pads allowed)
				(copperpour not_allowed)
				(footprints allowed)
			)
			(placement
				(enabled no)
				(sheetname "")
			)
			(fill
				(thermal_gap 0.5)
				(thermal_bridge_width 0.5)
				(island_removal_mode 0)
			)
			(polygon
				(pts
					(xy 344.043 -82.931) (xy 343.535 -82.931) (xy 343.535 -83.312) (xy 344.043 -83.312)
				)
			)
		)
	)
	(footprint ""
		(layer "B.Cu")
		(at 370.74348 -73.095358 90)
		(property "Reference" "C2R1"
			(at 0 0 90)
			(layer "B.SilkS")
			(hide yes)
			(effects
				(font
					(size 1.27 1.27)
				)
				(justify mirror)
			)
		)
		(property "Value" ""
			(at 0 0 90)
			(layer "B.Fab")
			(effects
				(font
					(size 1.27 1.27)
				)
				(justify mirror)
			)
		)
		(duplicate_pad_numbers_are_jumpers no)
		(fp_rect
			(start 0.2794 0.9144)
			(end -0.2794 -0.1143)
			(stroke
				(width 0)
				(type default)
			)
			(fill no)
			(layer "B.CrtYd")
		)
		(fp_line
			(start 0.2794 -0.1143)
			(end -0.2794 -0.1143)
			(stroke
				(width 0.1)
				(type default)
			)
			(layer "B.Fab")
		)
		(fp_line
			(start -0.2794 -0.1143)
			(end -0.2794 0.9144)
			(stroke
				(width 0.1)
				(type default)
			)
			(layer "B.Fab")
		)
		(fp_line
			(start 0.2794 0.9144)
			(end 0.2794 -0.1143)
			(stroke
				(width 0.1)
				(type default)
			)
			(layer "B.Fab")
		)
		(fp_line
			(start -0.2794 0.9144)
			(end 0.2794 0.9144)
			(stroke
				(width 0.1)
				(type default)
			)
			(layer "B.Fab")
		)
		(pad "1" smd custom
			(at 0 0)
			(size 0.10414 0.10414)
			(layers "B.Cu" "B.Mask" "B.Paste")
			(net "P3V3_STBY")
			(options
				(clearance outline)
				(anchor circle)
			)
			(primitives
				(gr_poly
					(pts
						(xy -0.20828 -0.08636) (xy -0.20828 0.08636) (xy -0.08636 0.20828) (xy 0.086614 0.20828) (xy 0.20828 0.086614)
						(xy 0.20828 -0.08636) (xy 0.08636 -0.20828) (xy -0.08636 -0.20828)
					)
					(width 0)
					(fill yes)
				)
			)
		)
		(pad "2" smd custom
			(at 0 0.8001)
			(size 0.10414 0.10414)
			(layers "B.Cu" "B.Mask" "B.Paste")
			(net "GND")
			(options
				(clearance outline)
				(anchor circle)
			)
			(primitives
				(gr_poly
					(pts
						(xy -0.20828 -0.08636) (xy -0.20828 0.08636) (xy -0.08636 0.20828) (xy 0.086614 0.20828) (xy 0.20828 0.086614)
						(xy 0.20828 -0.08636) (xy 0.08636 -0.20828) (xy -0.08636 -0.20828)
					)
					(width 0)
					(fill yes)
				)
			)
		)
		(zone
			(layer "B.Cu")
			(hatch none 0.5)
			(connect_pads
				(clearance 0)
			)
			(min_thickness 0.25)
			(keepout
				(tracks not_allowed)
				(vias allowed)
				(pads allowed)
				(copperpour not_allowed)
				(footprints allowed)
			)
			(placement
				(enabled no)
				(sheetname "")
			)
			(fill
				(thermal_gap 0.5)
				(thermal_bridge_width 0.5)
				(island_removal_mode 0)
			)
			(polygon
				(pts
					(xy 370.95303 -73.182988) (xy 371.33403 -73.182988) (xy 371.33403 -73.007728) (xy 370.95303 -73.007474)
				)
			)
		)
		(zone
			(layer "B.Cu")
			(hatch none 0.5)
			(connect_pads
				(clearance 0)
			)
			(min_thickness 0.25)
			(keepout
				(tracks allowed)
				(vias not_allowed)
				(pads allowed)
				(copperpour not_allowed)
				(footprints allowed)
			)
			(placement
				(enabled no)
				(sheetname "")
			)
			(fill
				(thermal_gap 0.5)
				(thermal_bridge_width 0.5)
				(island_removal_mode 0)
			)
			(polygon
				(pts
					(xy 370.95303 -73.182988) (xy 371.33403 -73.182988) (xy 371.33403 -73.007728) (xy 370.95303 -73.007474)
				)
			)
		)
	)
	(footprint ""
		(layer "B.Cu")
		(at 88.214708 -125.99162 90)
		(property "Reference" "SH7L1"
			(at 0 0 90)
			(layer "B.SilkS")
			(hide yes)
			(effects
				(font
					(size 1.27 1.27)
				)
				(justify mirror)
			)
		)
		(property "Value" ""
			(at 0 0 90)
			(layer "B.Fab")
			(effects
				(font
					(size 1.27 1.27)
				)
				(justify mirror)
			)
		)
		(duplicate_pad_numbers_are_jumpers no)
		(fp_poly
			(pts
				(xy 0.1651 -0.0508) (xy 0.1651 0.5842) (xy -0.1651 0.5842) (xy -0.1651 -0.0508)
			)
			(stroke
				(width 0)
				(type default)
			)
			(fill no)
			(layer "B.CrtYd")
		)
		(fp_line
			(start 0.1651 -0.0508)
			(end -0.1651 -0.0508)
			(stroke
				(width 0.1)
				(type default)
			)
			(layer "B.Fab")
		)
		(fp_line
			(start -0.1651 -0.0508)
			(end -0.1651 0.5842)
			(stroke
				(width 0.1)
				(type default)
			)
			(layer "B.Fab")
		)
		(fp_line
			(start 0.1651 0.5842)
			(end 0.1651 -0.0508)
			(stroke
				(width 0.1)
				(type default)
			)
			(layer "B.Fab")
		)
		(fp_line
			(start -0.1651 0.5842)
			(end 0.1651 0.5842)
			(stroke
				(width 0.1)
				(type default)
			)
			(layer "B.Fab")
		)
		(pad "1" smd custom
			(at 0 0 90)
			(size 0.0762 0.0762)
			(layers "B.Cu" "B.Mask" "B.Paste")
			(net "VSENSE_PVDDQ_KLM_N")
			(options
				(clearance outline)
				(anchor circle)
			)
			(primitives
				(gr_poly
					(pts
						(arc
							(start -0.1524 0.10795)
							(mid -0.098518 0.130268)
							(end -0.0762 0.18415)
						)
						(xy -0.0762 0.22225) (xy 0.0762 0.22225)
						(arc
							(start 0.0762 0.18415)
							(mid 0.098518 0.130268)
							(end 0.1524 0.10795)
						)
						(xy 0.1524 -0.22225) (xy -0.1524 -0.22225)
					)
					(width 0)
					(fill yes)
				)
			)
		)
		(pad "2" smd custom
			(at 0 0.5334 270)
			(size 0.0762 0.0762)
			(layers "B.Cu" "B.Mask" "B.Paste")
			(net "GND")
			(options
				(clearance outline)
				(anchor circle)
			)
			(primitives
				(gr_poly
					(pts
						(arc
							(start -0.1524 0.10795)
							(mid -0.098518 0.130268)
							(end -0.0762 0.18415)
						)
						(xy -0.0762 0.22225) (xy 0.0762 0.22225)
						(arc
							(start 0.0762 0.18415)
							(mid 0.098518 0.130268)
							(end 0.1524 0.10795)
						)
						(xy 0.1524 -0.22225) (xy -0.1524 -0.22225)
					)
					(width 0)
					(fill yes)
				)
			)
		)
	)
)
